(kicad_pcb
	(version 20260206)
	(generator "pcbnew")
	(generator_version "10.0")
	(general
		(thickness 1.6)
		(legacy_teardrops no)
	)
	(paper "A4")
	(title_block
		(title "04192023_DAF0TMB3IC0_F0TG_MB_C_brd_V02_OCP.brd")
		(comment 1 "Grand Teton / footprints 5167-5174 of 8354")
	)
	(layers
		(0 "F.Cu" signal "TOP")
		(4 "In1.Cu" signal "GND")
		(6 "In2.Cu" signal "IN1")
		(8 "In3.Cu" signal "GND1")
		(10 "In4.Cu" signal "IN2")
		(12 "In5.Cu" signal "GND2")
		(14 "In6.Cu" signal "IN3")
		(16 "In7.Cu" signal "GND3")
		(18 "In8.Cu" signal "VCC")
		(20 "In9.Cu" signal "VCC1")
		(22 "In10.Cu" signal "GND4")
		(24 "In11.Cu" signal "IN4")
		(26 "In12.Cu" signal "GND5")
		(28 "In13.Cu" signal "IN5")
		(30 "In14.Cu" signal "GND6")
		(32 "In15.Cu" signal "IN6")
		(34 "In16.Cu" signal "GND7")
		(2 "B.Cu" signal "BOTTOM")
		(9 "F.Adhes" user "F.Adhesive")
		(11 "B.Adhes" user "B.Adhesive")
		(13 "F.Paste" user "Package Geometry/Pastemask Top")
		(15 "B.Paste" user "Package Geometry/Pastemask Bottom")
		(5 "F.SilkS" user "Ref Des/Silkscreen Top")
		(7 "B.SilkS" user "Ref Des/Silkscreen Bottom")
		(1 "F.Mask" user "Board Geometry/Soldermask Top")
		(3 "B.Mask" user "Board Geometry/Soldermask Bottom")
		(17 "Dwgs.User" user "User.Drawings")
		(19 "Cmts.User" user "User.Comments")
		(21 "Eco1.User" user "User.Eco1")
		(23 "Eco2.User" user "User.Eco2")
		(25 "Edge.Cuts" user "Board Geometry/Outline")
		(27 "Margin" user)
		(31 "F.CrtYd" user "Package Geometry/Place Bound Top")
		(29 "B.CrtYd" user "Package Geometry/Place Bound Bottom")
		(35 "F.Fab" user "Ref Des/Assembly Top")
		(33 "B.Fab" user "Ref Des/Assembly Bottom")
	)
	(footprint ""
		(layer "B.Cu")
		(at 234.81157 -323.746114 180)
		(property "Reference" "R1221"
			(at 0 0 0)
			(layer "B.SilkS")
			(hide yes)
			(effects
				(font
					(size 1.27 1.27)
				)
				(justify mirror)
			)
		)
		(property "Value" ""
			(at 0 0 0)
			(layer "B.Fab")
			(effects
				(font
					(size 1.27 1.27)
				)
				(justify mirror)
			)
		)
		(duplicate_pad_numbers_are_jumpers no)
		(fp_line
			(start 0.7874 0.4064)
			(end 0.7874 -0.4064)
			(stroke
				(width 0.1524)
				(type default)
			)
			(layer "B.SilkS")
		)
		(fp_line
			(start 0.7874 -0.4064)
			(end -0.7874 -0.4064)
			(stroke
				(width 0.1524)
				(type default)
			)
			(layer "B.SilkS")
		)
		(fp_line
			(start -0.7874 0.4064)
			(end 0.7874 0.4064)
			(stroke
				(width 0.1524)
				(type default)
			)
			(layer "B.SilkS")
		)
		(fp_line
			(start -0.7874 -0.4064)
			(end -0.7874 0.4064)
			(stroke
				(width 0.1524)
				(type default)
			)
			(layer "B.SilkS")
		)
		(fp_line
			(start 0.67945 0.3048)
			(end 0.67945 -0.305054)
			(stroke
				(width 0.1)
				(type default)
			)
			(layer "B.Fab")
		)
		(fp_line
			(start 0.67945 -0.305054)
			(end 0.12065 -0.305054)
			(stroke
				(width 0.1)
				(type default)
			)
			(layer "B.Fab")
		)
		(fp_line
			(start 0.12065 0.3048)
			(end 0.67945 0.3048)
			(stroke
				(width 0.1)
				(type default)
			)
			(layer "B.Fab")
		)
		(fp_line
			(start 0.12065 0.2794)
			(end 0.12065 0.3048)
			(stroke
				(width 0.1)
				(type default)
			)
			(layer "B.Fab")
		)
		(fp_line
			(start 0.12065 -0.2794)
			(end -0.12065 -0.2794)
			(stroke
				(width 0.1)
				(type default)
			)
			(layer "B.Fab")
		)
		(fp_line
			(start 0.12065 -0.305054)
			(end 0.12065 -0.2794)
			(stroke
				(width 0.1)
				(type default)
			)
			(layer "B.Fab")
		)
		(fp_line
			(start -0.120396 0.3048)
			(end -0.120396 0.2794)
			(stroke
				(width 0.1)
				(type default)
			)
			(layer "B.Fab")
		)
		(fp_line
			(start -0.120396 0.2794)
			(end 0.12065 0.2794)
			(stroke
				(width 0.1)
				(type default)
			)
			(layer "B.Fab")
		)
		(fp_line
			(start -0.12065 -0.2794)
			(end -0.12065 -0.3048)
			(stroke
				(width 0.1)
				(type default)
			)
			(layer "B.Fab")
		)
		(fp_line
			(start -0.12065 -0.3048)
			(end -0.67945 -0.3048)
			(stroke
				(width 0.1)
				(type default)
			)
			(layer "B.Fab")
		)
		(fp_line
			(start -0.67945 0.3048)
			(end -0.120396 0.3048)
			(stroke
				(width 0.1)
				(type default)
			)
			(layer "B.Fab")
		)
		(fp_line
			(start -0.67945 -0.3048)
			(end -0.67945 0.3048)
			(stroke
				(width 0.1)
				(type default)
			)
			(layer "B.Fab")
		)
		(pad "1" smd circle
			(at 0.40005 0)
			(size 0 0)
			(layers "B.Cu" "B.Mask" "B.Paste")
			(net "P1V2_AUX_ADC")
		)
		(pad "2" smd circle
			(at -0.40005 0)
			(size 0 0)
			(layers "B.Cu" "B.Mask" "B.Paste")
			(net "GND")
		)
	)
	(footprint ""
		(layer "B.Cu")
		(at 34.034476 -338.010754 -90)
		(property "Reference" "PC635_3"
			(at 0 0 90)
			(layer "B.SilkS")
			(hide yes)
			(effects
				(font
					(size 1.27 1.27)
				)
				(justify mirror)
			)
		)
		(property "Value" ""
			(at 0 0 90)
			(layer "B.Fab")
			(effects
				(font
					(size 1.27 1.27)
				)
				(justify mirror)
			)
		)
		(duplicate_pad_numbers_are_jumpers no)
		(fp_line
			(start -1.524 0.762)
			(end 1.524 0.762)
			(stroke
				(width 0.1524)
				(type default)
			)
			(layer "B.SilkS")
		)
		(fp_line
			(start 1.524 0.762)
			(end 1.524 -0.762)
			(stroke
				(width 0.1524)
				(type default)
			)
			(layer "B.SilkS")
		)
		(fp_line
			(start -1.524 -0.762)
			(end -1.524 0.762)
			(stroke
				(width 0.1524)
				(type default)
			)
			(layer "B.SilkS")
		)
		(fp_line
			(start 1.524 -0.762)
			(end -1.524 -0.762)
			(stroke
				(width 0.1524)
				(type default)
			)
			(layer "B.SilkS")
		)
		(fp_line
			(start -1.1049 0.724916)
			(end -1.1049 -0.724916)
			(stroke
				(width 0.1)
				(type default)
			)
			(layer "B.Fab")
		)
		(fp_line
			(start 1.1049 0.724916)
			(end -1.1049 0.724916)
			(stroke
				(width 0.1)
				(type default)
			)
			(layer "B.Fab")
		)
		(fp_line
			(start -1.1049 -0.724916)
			(end 1.1049 -0.724916)
			(stroke
				(width 0.1)
				(type default)
			)
			(layer "B.Fab")
		)
		(fp_line
			(start 1.1049 -0.724916)
			(end 1.1049 0.724916)
			(stroke
				(width 0.1)
				(type default)
			)
			(layer "B.Fab")
		)
		(pad "1" smd rect
			(at 0.889 0 270)
			(size 1.016 1.27)
			(layers "B.Cu" "B.Mask" "B.Paste")
			(net "PVDDIO_P1")
		)
		(pad "2" smd rect
			(at -0.889 0 270)
			(size 1.016 1.27)
			(layers "B.Cu" "B.Mask" "B.Paste")
			(net "GND")
		)
	)
	(footprint ""
		(layer "B.Cu")
		(at 391.694162 -416.899344 90)
		(property "Reference" "C6609"
			(at 0 0 90)
			(layer "B.SilkS")
			(hide yes)
			(effects
				(font
					(size 1.27 1.27)
				)
				(justify mirror)
			)
		)
		(property "Value" ""
			(at 0 0 90)
			(layer "B.Fab")
			(effects
				(font
					(size 1.27 1.27)
				)
				(justify mirror)
			)
		)
		(duplicate_pad_numbers_are_jumpers no)
		(fp_line
			(start 0.299974 -0.150114)
			(end -0.299974 -0.150114)
			(stroke
				(width 0.1)
				(type default)
			)
			(layer "B.Fab")
		)
		(fp_line
			(start -0.299974 -0.150114)
			(end -0.299974 0.150114)
			(stroke
				(width 0.1)
				(type default)
			)
			(layer "B.Fab")
		)
		(fp_line
			(start 0.299974 0.150114)
			(end 0.299974 -0.150114)
			(stroke
				(width 0.1)
				(type default)
			)
			(layer "B.Fab")
		)
		(fp_line
			(start -0.299974 0.150114)
			(end 0.299974 0.150114)
			(stroke
				(width 0.1)
				(type default)
			)
			(layer "B.Fab")
		)
		(pad "1" smd rect
			(at 0.2667 0 270)
			(size 0.3048 0.381)
			(layers "B.Cu" "B.Mask" "B.Paste")
			(net "P5E_CPU0_P3_TX_BUF_C_DP<6>")
		)
		(pad "2" smd rect
			(at -0.2667 0 270)
			(size 0.3048 0.381)
			(layers "B.Cu" "B.Mask" "B.Paste")
			(net "P5E_CPU0_P3_TX_BUF_DP<6>")
		)
	)
	(footprint ""
		(layer "B.Cu")
		(at 79.886302 -338.93252 -90)
		(property "Reference" "PC385_2"
			(at 0 0 90)
			(layer "B.SilkS")
			(hide yes)
			(effects
				(font
					(size 1.27 1.27)
				)
				(justify mirror)
			)
		)
		(property "Value" ""
			(at 0 0 90)
			(layer "B.Fab")
			(effects
				(font
					(size 1.27 1.27)
				)
				(justify mirror)
			)
		)
		(duplicate_pad_numbers_are_jumpers no)
		(fp_line
			(start -1.524 0.762)
			(end 1.524 0.762)
			(stroke
				(width 0.1524)
				(type default)
			)
			(layer "B.SilkS")
		)
		(fp_line
			(start 1.524 0.762)
			(end 1.524 -0.762)
			(stroke
				(width 0.1524)
				(type default)
			)
			(layer "B.SilkS")
		)
		(fp_line
			(start -1.524 -0.762)
			(end -1.524 0.762)
			(stroke
				(width 0.1524)
				(type default)
			)
			(layer "B.SilkS")
		)
		(fp_line
			(start 1.524 -0.762)
			(end -1.524 -0.762)
			(stroke
				(width 0.1524)
				(type default)
			)
			(layer "B.SilkS")
		)
		(fp_line
			(start -1.1049 0.724916)
			(end -1.1049 -0.724916)
			(stroke
				(width 0.1)
				(type default)
			)
			(layer "B.Fab")
		)
		(fp_line
			(start 1.1049 0.724916)
			(end -1.1049 0.724916)
			(stroke
				(width 0.1)
				(type default)
			)
			(layer "B.Fab")
		)
		(fp_line
			(start -1.1049 -0.724916)
			(end 1.1049 -0.724916)
			(stroke
				(width 0.1)
				(type default)
			)
			(layer "B.Fab")
		)
		(fp_line
			(start 1.1049 -0.724916)
			(end 1.1049 0.724916)
			(stroke
				(width 0.1)
				(type default)
			)
			(layer "B.Fab")
		)
		(pad "1" smd rect
			(at 0.889 0 270)
			(size 1.016 1.27)
			(layers "B.Cu" "B.Mask" "B.Paste")
			(net "SW_P12V_AUX_PVDDCR_CPU1_P1_FLT")
		)
		(pad "2" smd rect
			(at -0.889 0 270)
			(size 1.016 1.27)
			(layers "B.Cu" "B.Mask" "B.Paste")
			(net "GND")
		)
	)
	(footprint ""
		(layer "B.Cu")
		(at 371.551454 -249.36831)
		(property "Reference" "C274"
			(at 0 0 0)
			(layer "B.SilkS")
			(hide yes)
			(effects
				(font
					(size 1.27 1.27)
				)
				(justify mirror)
			)
		)
		(property "Value" ""
			(at 0 0 0)
			(layer "B.Fab")
			(effects
				(font
					(size 1.27 1.27)
				)
				(justify mirror)
			)
		)
		(duplicate_pad_numbers_are_jumpers no)
		(fp_line
			(start -0.7874 -0.4064)
			(end -0.7874 0.4064)
			(stroke
				(width 0.1524)
				(type default)
			)
			(layer "B.SilkS")
		)
		(fp_line
			(start -0.7874 0.4064)
			(end 0.7874 0.4064)
			(stroke
				(width 0.1524)
				(type default)
			)
			(layer "B.SilkS")
		)
		(fp_line
			(start 0.7874 -0.4064)
			(end -0.7874 -0.4064)
			(stroke
				(width 0.1524)
				(type default)
			)
			(layer "B.SilkS")
		)
		(fp_line
			(start 0.7874 0.4064)
			(end 0.7874 -0.4064)
			(stroke
				(width 0.1524)
				(type default)
			)
			(layer "B.SilkS")
		)
		(fp_line
			(start -0.67945 -0.3048)
			(end -0.67945 0.3048)
			(stroke
				(width 0.1)
				(type default)
			)
			(layer "B.Fab")
		)
		(fp_line
			(start -0.67945 0.3048)
			(end -0.120396 0.3048)
			(stroke
				(width 0.1)
				(type default)
			)
			(layer "B.Fab")
		)
		(fp_line
			(start -0.12065 -0.3048)
			(end -0.67945 -0.3048)
			(stroke
				(width 0.1)
				(type default)
			)
			(layer "B.Fab")
		)
		(fp_line
			(start -0.12065 -0.2794)
			(end -0.12065 -0.3048)
			(stroke
				(width 0.1)
				(type default)
			)
			(layer "B.Fab")
		)
		(fp_line
			(start -0.120396 0.2794)
			(end 0.12065 0.2794)
			(stroke
				(width 0.1)
				(type default)
			)
			(layer "B.Fab")
		)
		(fp_line
			(start -0.120396 0.3048)
			(end -0.120396 0.2794)
			(stroke
				(width 0.1)
				(type default)
			)
			(layer "B.Fab")
		)
		(fp_line
			(start 0.12065 -0.305054)
			(end 0.12065 -0.2794)
			(stroke
				(width 0.1)
				(type default)
			)
			(layer "B.Fab")
		)
		(fp_line
			(start 0.12065 -0.2794)
			(end -0.12065 -0.2794)
			(stroke
				(width 0.1)
				(type default)
			)
			(layer "B.Fab")
		)
		(fp_line
			(start 0.12065 0.2794)
			(end 0.12065 0.3048)
			(stroke
				(width 0.1)
				(type default)
			)
			(layer "B.Fab")
		)
		(fp_line
			(start 0.12065 0.3048)
			(end 0.67945 0.3048)
			(stroke
				(width 0.1)
				(type default)
			)
			(layer "B.Fab")
		)
		(fp_line
			(start 0.67945 -0.305054)
			(end 0.12065 -0.305054)
			(stroke
				(width 0.1)
				(type default)
			)
			(layer "B.Fab")
		)
		(fp_line
			(start 0.67945 0.3048)
			(end 0.67945 -0.305054)
			(stroke
				(width 0.1)
				(type default)
			)
			(layer "B.Fab")
		)
		(pad "1" smd circle
			(at 0.40005 0 180)
			(size 0 0)
			(layers "B.Cu" "B.Mask" "B.Paste")
			(net "PVDDCR_CPU0_P0")
		)
		(pad "2" smd circle
			(at -0.40005 0 180)
			(size 0 0)
			(layers "B.Cu" "B.Mask" "B.Paste")
			(net "GND")
		)
	)
	(footprint ""
		(layer "B.Cu")
		(at 236.8169 -249.555 180)
		(property "Reference" "R327"
			(at 0 0 0)
			(layer "B.SilkS")
			(hide yes)
			(effects
				(font
					(size 1.27 1.27)
				)
				(justify mirror)
			)
		)
		(property "Value" ""
			(at 0 0 0)
			(layer "B.Fab")
			(effects
				(font
					(size 1.27 1.27)
				)
				(justify mirror)
			)
		)
		(duplicate_pad_numbers_are_jumpers no)
		(fp_line
			(start 0.7874 0.4064)
			(end 0.7874 -0.4064)
			(stroke
				(width 0.1524)
				(type default)
			)
			(layer "B.SilkS")
		)
		(fp_line
			(start 0.7874 -0.4064)
			(end -0.7874 -0.4064)
			(stroke
				(width 0.1524)
				(type default)
			)
			(layer "B.SilkS")
		)
		(fp_line
			(start -0.7874 0.4064)
			(end 0.7874 0.4064)
			(stroke
				(width 0.1524)
				(type default)
			)
			(layer "B.SilkS")
		)
		(fp_line
			(start -0.7874 -0.4064)
			(end -0.7874 0.4064)
			(stroke
				(width 0.1524)
				(type default)
			)
			(layer "B.SilkS")
		)
		(fp_line
			(start 0.67945 0.3048)
			(end 0.67945 -0.305054)
			(stroke
				(width 0.1)
				(type default)
			)
			(layer "B.Fab")
		)
		(fp_line
			(start 0.67945 -0.305054)
			(end 0.12065 -0.305054)
			(stroke
				(width 0.1)
				(type default)
			)
			(layer "B.Fab")
		)
		(fp_line
			(start 0.12065 0.3048)
			(end 0.67945 0.3048)
			(stroke
				(width 0.1)
				(type default)
			)
			(layer "B.Fab")
		)
		(fp_line
			(start 0.12065 0.2794)
			(end 0.12065 0.3048)
			(stroke
				(width 0.1)
				(type default)
			)
			(layer "B.Fab")
		)
		(fp_line
			(start 0.12065 -0.2794)
			(end -0.12065 -0.2794)
			(stroke
				(width 0.1)
				(type default)
			)
			(layer "B.Fab")
		)
		(fp_line
			(start 0.12065 -0.305054)
			(end 0.12065 -0.2794)
			(stroke
				(width 0.1)
				(type default)
			)
			(layer "B.Fab")
		)
		(fp_line
			(start -0.120396 0.3048)
			(end -0.120396 0.2794)
			(stroke
				(width 0.1)
				(type default)
			)
			(layer "B.Fab")
		)
		(fp_line
			(start -0.120396 0.2794)
			(end 0.12065 0.2794)
			(stroke
				(width 0.1)
				(type default)
			)
			(layer "B.Fab")
		)
		(fp_line
			(start -0.12065 -0.2794)
			(end -0.12065 -0.3048)
			(stroke
				(width 0.1)
				(type default)
			)
			(layer "B.Fab")
		)
		(fp_line
			(start -0.12065 -0.3048)
			(end -0.67945 -0.3048)
			(stroke
				(width 0.1)
				(type default)
			)
			(layer "B.Fab")
		)
		(fp_line
			(start -0.67945 0.3048)
			(end -0.120396 0.3048)
			(stroke
				(width 0.1)
				(type default)
			)
			(layer "B.Fab")
		)
		(fp_line
			(start -0.67945 -0.3048)
			(end -0.67945 0.3048)
			(stroke
				(width 0.1)
				(type default)
			)
			(layer "B.Fab")
		)
		(pad "1" smd rect
			(at 0.40005 0 180)
			(size 0.4572 0.508)
			(layers "B.Cu" "B.Mask" "B.Paste")
			(net "SMB_APML_CPU0_MUX2_SCL")
		)
		(pad "2" smd rect
			(at -0.40005 0 180)
			(size 0.4572 0.508)
			(layers "B.Cu" "B.Mask" "B.Paste")
			(net "SMB_APML_CPU0_SCL")
		)
	)
	(footprint ""
		(layer "B.Cu")
		(at 113.375948 -256.012442 -90)
		(property "Reference" "C3908"
			(at 0 0 90)
			(layer "B.SilkS")
			(hide yes)
			(effects
				(font
					(size 1.27 1.27)
				)
				(justify mirror)
			)
		)
		(property "Value" ""
			(at 0 0 90)
			(layer "B.Fab")
			(effects
				(font
					(size 1.27 1.27)
				)
				(justify mirror)
			)
		)
		(duplicate_pad_numbers_are_jumpers no)
		(fp_line
			(start -0.7874 0.4064)
			(end 0.7874 0.4064)
			(stroke
				(width 0.1524)
				(type default)
			)
			(layer "B.SilkS")
		)
		(fp_line
			(start 0.7874 0.4064)
			(end 0.7874 -0.4064)
			(stroke
				(width 0.1524)
				(type default)
			)
			(layer "B.SilkS")
		)
		(fp_line
			(start -0.7874 -0.4064)
			(end -0.7874 0.4064)
			(stroke
				(width 0.1524)
				(type default)
			)
			(layer "B.SilkS")
		)
		(fp_line
			(start 0.7874 -0.4064)
			(end -0.7874 -0.4064)
			(stroke
				(width 0.1524)
				(type default)
			)
			(layer "B.SilkS")
		)
		(fp_line
			(start -0.67945 0.3048)
			(end -0.120396 0.3048)
			(stroke
				(width 0.1)
				(type default)
			)
			(layer "B.Fab")
		)
		(fp_line
			(start -0.120396 0.3048)
			(end -0.120396 0.2794)
			(stroke
				(width 0.1)
				(type default)
			)
			(layer "B.Fab")
		)
		(fp_line
			(start 0.12065 0.3048)
			(end 0.67945 0.3048)
			(stroke
				(width 0.1)
				(type default)
			)
			(layer "B.Fab")
		)
		(fp_line
			(start 0.67945 0.3048)
			(end 0.67945 -0.305054)
			(stroke
				(width 0.1)
				(type default)
			)
			(layer "B.Fab")
		)
		(fp_line
			(start -0.120396 0.2794)
			(end 0.12065 0.2794)
			(stroke
				(width 0.1)
				(type default)
			)
			(layer "B.Fab")
		)
		(fp_line
			(start 0.12065 0.2794)
			(end 0.12065 0.3048)
			(stroke
				(width 0.1)
				(type default)
			)
			(layer "B.Fab")
		)
		(fp_line
			(start -0.12065 -0.2794)
			(end -0.12065 -0.3048)
			(stroke
				(width 0.1)
				(type default)
			)
			(layer "B.Fab")
		)
		(fp_line
			(start 0.12065 -0.2794)
			(end -0.12065 -0.2794)
			(stroke
				(width 0.1)
				(type default)
			)
			(layer "B.Fab")
		)
		(fp_line
			(start -0.67945 -0.3048)
			(end -0.67945 0.3048)
			(stroke
				(width 0.1)
				(type default)
			)
			(layer "B.Fab")
		)
		(fp_line
			(start -0.12065 -0.3048)
			(end -0.67945 -0.3048)
			(stroke
				(width 0.1)
				(type default)
			)
			(layer "B.Fab")
		)
		(fp_line
			(start 0.12065 -0.305054)
			(end 0.12065 -0.2794)
			(stroke
				(width 0.1)
				(type default)
			)
			(layer "B.Fab")
		)
		(fp_line
			(start 0.67945 -0.305054)
			(end 0.12065 -0.305054)
			(stroke
				(width 0.1)
				(type default)
			)
			(layer "B.Fab")
		)
		(pad "1" smd circle
			(at 0.40005 0 90)
			(size 0 0)
			(layers "B.Cu" "B.Mask" "B.Paste")
			(net "PVDDCR_SOC_P1")
		)
		(pad "2" smd circle
			(at -0.40005 0 90)
			(size 0 0)
			(layers "B.Cu" "B.Mask" "B.Paste")
			(net "GND")
		)
	)
	(footprint ""
		(layer "B.Cu")
		(at 127.818388 -388.011162 -90)
		(property "Reference" "C464"
			(at 0 0 90)
			(layer "B.SilkS")
			(hide yes)
			(effects
				(font
					(size 1.27 1.27)
				)
				(justify mirror)
			)
		)
		(property "Value" ""
			(at 0 0 90)
			(layer "B.Fab")
			(effects
				(font
					(size 1.27 1.27)
				)
				(justify mirror)
			)
		)
		(duplicate_pad_numbers_are_jumpers no)
		(fp_line
			(start -0.299974 0.150114)
			(end 0.299974 0.150114)
			(stroke
				(width 0.1)
				(type default)
			)
			(layer "B.Fab")
		)
		(fp_line
			(start 0.299974 0.150114)
			(end 0.299974 -0.150114)
			(stroke
				(width 0.1)
				(type default)
			)
			(layer "B.Fab")
		)
		(fp_line
			(start -0.299974 -0.150114)
			(end -0.299974 0.150114)
			(stroke
				(width 0.1)
				(type default)
			)
			(layer "B.Fab")
		)
		(fp_line
			(start 0.299974 -0.150114)
			(end -0.299974 -0.150114)
			(stroke
				(width 0.1)
				(type default)
			)
			(layer "B.Fab")
		)
		(pad "1" smd rect
			(at 0.2667 0 90)
			(size 0.3048 0.381)
			(layers "B.Cu" "B.Mask" "B.Paste")
			(net "P0V9_CPU1_RT3_2A_2D")
		)
		(pad "2" smd rect
			(at -0.2667 0 90)
			(size 0.3048 0.381)
			(layers "B.Cu" "B.Mask" "B.Paste")
			(net "GND")
		)
	)
)
